# TIMECARD (Time Appliance Project (Time Card)) — schematic netlist excerpt (pin names and nets, part order shuffled) for the footprints in the layout excerpt that follows; sources: Cadence DE-HDL packaged netlist, KiCad conversion of R4006-B0001-02_R01.brd

C113  CAPACITOR  0.1UF 10V 10%  pkg SMC_0402R_H022  page 14 : \1\ = XP1R8V_FPGA_VCCAUX ; \2\ = SG
C34  CAPACITOR  0.1UF 10%  pkg SMC_0402R_H022  page 9 : \1\ = C_CPU_RX_PCIE_MGT2_TXN ; \2\ = CPU_RX_PCIE_MGT2_TXN

(kicad_pcb
	(version 20260206)
	(generator "pcbnew")
	(generator_version "10.0")
	(general
		(thickness 1.6)
		(legacy_teardrops no)
	)
	(paper "A4")
	(title_block
		(title "timecard-production-celestica-r4006 — R4006-B0001-02_R01.brd")
		(comment 1 "Time Appliance Project (Time Card) / footprints 1089-1090 of 1113")
	)
	(layers
		(0 "F.Cu" signal "TOP")
		(4 "In1.Cu" signal "L02_GND1")
		(6 "In2.Cu" signal "L03_SIG1")
		(8 "In3.Cu" signal "L04_GND2")
		(10 "In4.Cu" signal "L05_VCC1")
		(12 "In5.Cu" signal "L06_VCC2")
		(14 "In6.Cu" signal "L07_GND3")
		(16 "In7.Cu" signal "L08_SIG2")
		(18 "In8.Cu" signal "L09_GND4")
		(2 "B.Cu" signal "BOTTOM")
		(9 "F.Adhes" user "F.Adhesive")
		(11 "B.Adhes" user "B.Adhesive")
		(13 "F.Paste" user "Package Geometry/Pastemask Top")
		(15 "B.Paste" user "Package Geometry/Pastemask Bottom")
		(5 "F.SilkS" user "Ref Des/Silkscreen Top")
		(7 "B.SilkS" user "Ref Des/Silkscreen Bottom")
		(1 "F.Mask" user "Board Geometry/Soldermask Top")
		(3 "B.Mask" user "Board Geometry/Soldermask Bottom")
		(17 "Dwgs.User" user "User.Drawings")
		(19 "Cmts.User" user "User.Comments")
		(21 "Eco1.User" user "User.Eco1")
		(23 "Eco2.User" user "User.Eco2")
		(25 "Edge.Cuts" user "Board Geometry/Outline")
		(27 "Margin" user)
		(31 "F.CrtYd" user "Package Geometry/Place Bound Top")
		(29 "B.CrtYd" user "Package Geometry/Place Bound Bottom")
		(35 "F.Fab" user "Ref Des/Assembly Top")
		(33 "B.Fab" user "Ref Des/Assembly Bottom")
	)
	(footprint ""
		(layer "B.Cu")
		(at 72.40397 -15.367 -90)
		(property "Reference" "C34"
			(at 2.286 -0.08128 270)
			(unlocked yes)
			(layer "B.SilkS")
			(effects
				(font
					(size 0.635 0.4064)
					(thickness 0.1524)
				)
				(justify mirror)
			)
		)
		(property "Value" "VAL*"
			(at -0.0762 2.067306 270)
			(unlocked yes)
			(layer "B.Fab")
			(hide yes)
			(effects
				(font
					(size 0.7874 0.5842)
					(thickness 0.1524)
				)
				(justify mirror)
			)
		)
		(property "Tolerance" "TOL*"
			(at -0.0762 3.032506 270)
			(unlocked yes)
			(layer "Cmts.User")
			(hide yes)
			(effects
				(font
					(size 0.7874 0.5842)
					(thickness 0.1524)
				)
				(justify mirror)
			)
		)
		(property "User Part Number" "PARTNUM*"
			(at -0.1016 4.023106 270)
			(unlocked yes)
			(layer "Cmts.User")
			(hide yes)
			(effects
				(font
					(size 0.7874 0.5842)
					(thickness 0.1524)
				)
				(justify mirror)
			)
		)
		(property "Device Type" "CAPACITOR-G105-0B104-CK,0.1UF,A"
			(at -0.0508 1.127506 270)
			(unlocked yes)
			(layer "B.Fab")
			(hide yes)
			(effects
				(font
					(size 0.7874 0.5842)
					(thickness 0.1524)
				)
				(justify mirror)
			)
		)
		(duplicate_pad_numbers_are_jumpers no)
		(fp_line
			(start -1.143 0.5588)
			(end -1.143 -0.5588)
			(stroke
				(width 0.1)
				(type default)
			)
			(layer "B.SilkS")
		)
		(fp_line
			(start 1.143 0.5588)
			(end -1.143 0.5588)
			(stroke
				(width 0.1)
				(type default)
			)
			(layer "B.SilkS")
		)
		(fp_line
			(start -1.143 -0.5588)
			(end 1.143 -0.5588)
			(stroke
				(width 0.1)
				(type default)
			)
			(layer "B.SilkS")
		)
		(fp_line
			(start 1.143 -0.5588)
			(end 1.143 0.5588)
			(stroke
				(width 0.1)
				(type default)
			)
			(layer "B.SilkS")
		)
		(fp_rect
			(start 1.143 0.5588)
			(end -1.143 -0.5588)
			(stroke
				(width 0)
				(type default)
			)
			(fill no)
			(layer "B.CrtYd")
		)
		(fp_line
			(start -0.508 0.3048)
			(end -0.508 -0.3048)
			(stroke
				(width 0.1)
				(type default)
			)
			(layer "B.Fab")
		)
		(fp_line
			(start 0.508 0.3048)
			(end -0.508 0.3048)
			(stroke
				(width 0.1)
				(type default)
			)
			(layer "B.Fab")
		)
		(fp_line
			(start -0.508 -0.3048)
			(end 0.508 -0.3048)
			(stroke
				(width 0.1)
				(type default)
			)
			(layer "B.Fab")
		)
		(fp_line
			(start 0.508 -0.3048)
			(end 0.508 0.3048)
			(stroke
				(width 0.1)
				(type default)
			)
			(layer "B.Fab")
		)
		(pad "1" smd rect
			(at 0.5334 0 90)
			(size 0.7112 0.6096)
			(layers "B.Cu" "B.Mask" "B.Paste")
			(net "C_CPU_RX_PCIE_MGT2_TXN")
		)
		(pad "2" smd rect
			(at -0.5334 0 90)
			(size 0.7112 0.6096)
			(layers "B.Cu" "B.Mask" "B.Paste")
			(net "CPU_RX_PCIE_MGT2_TXN")
		)
		(zone
			(layer "B.Cu")
			(hatch none 0.5)
			(connect_pads
				(clearance 0)
			)
			(min_thickness 0.25)
			(keepout
				(tracks allowed)
				(vias not_allowed)
				(pads allowed)
				(copperpour not_allowed)
				(footprints allowed)
			)
			(placement
				(enabled no)
				(sheetname "")
			)
			(fill
				(thermal_gap 0.5)
				(thermal_bridge_width 0.5)
				(island_removal_mode 0)
			)
			(polygon
				(pts
					(xy 72.09917 -15.2908) (xy 72.70877 -15.2908) (xy 72.70877 -15.4432) (xy 72.09917 -15.4432)
				)
			)
		)
	)
	(footprint ""
		(layer "B.Cu")
		(at 104.6226 -44.45)
		(property "Reference" "C113"
			(at -43.307 1.63195 0)
			(unlocked yes)
			(layer "B.SilkS")
			(effects
				(font
					(size 0.635 0.4064)
					(thickness 0.1524)
				)
				(justify mirror)
			)
		)
		(property "Value" "VAL*"
			(at -0.0762 2.067306 0)
			(unlocked yes)
			(layer "B.Fab")
			(hide yes)
			(effects
				(font
					(size 0.7874 0.5842)
					(thickness 0.1524)
				)
				(justify mirror)
			)
		)
		(property "Device Type" "CAPACITOR-G105-0B104-CK,0.1UF,A"
			(at -0.0508 1.127506 0)
			(unlocked yes)
			(layer "B.Fab")
			(hide yes)
			(effects
				(font
					(size 0.7874 0.5842)
					(thickness 0.1524)
				)
				(justify mirror)
			)
		)
		(property "User Part Number" "PARTNUM*"
			(at -0.1016 4.023106 0)
			(unlocked yes)
			(layer "Cmts.User")
			(hide yes)
			(effects
				(font
					(size 0.7874 0.5842)
					(thickness 0.1524)
				)
				(justify mirror)
			)
		)
		(property "Tolerance" "TOL*"
			(at -0.0762 3.032506 0)
			(unlocked yes)
			(layer "Cmts.User")
			(hide yes)
			(effects
				(font
					(size 0.7874 0.5842)
					(thickness 0.1524)
				)
				(justify mirror)
			)
		)
		(duplicate_pad_numbers_are_jumpers no)
		(fp_line
			(start -1.143 -0.5588)
			(end 1.143 -0.5588)
			(stroke
				(width 0.1)
				(type default)
			)
			(layer "B.SilkS")
		)
		(fp_line
			(start -1.143 0.5588)
			(end -1.143 -0.5588)
			(stroke
				(width 0.1)
				(type default)
			)
			(layer "B.SilkS")
		)
		(fp_line
			(start 1.143 -0.5588)
			(end 1.143 0.5588)
			(stroke
				(width 0.1)
				(type default)
			)
			(layer "B.SilkS")
		)
		(fp_line
			(start 1.143 0.5588)
			(end -1.143 0.5588)
			(stroke
				(width 0.1)
				(type default)
			)
			(layer "B.SilkS")
		)
		(fp_poly
			(pts
				(xy 1.143 0.5588) (xy -1.143 0.5588) (xy -1.143 -0.5588) (xy 1.143 -0.5588)
			)
			(stroke
				(width 0)
				(type default)
			)
			(fill no)
			(layer "B.CrtYd")
		)
		(fp_line
			(start -0.508 -0.3048)
			(end 0.508 -0.3048)
			(stroke
				(width 0.1)
				(type default)
			)
			(layer "B.Fab")
		)
		(fp_line
			(start -0.508 0.3048)
			(end -0.508 -0.3048)
			(stroke
				(width 0.1)
				(type default)
			)
			(layer "B.Fab")
		)
		(fp_line
			(start 0.508 -0.3048)
			(end 0.508 0.3048)
			(stroke
				(width 0.1)
				(type default)
			)
			(layer "B.Fab")
		)
		(fp_line
			(start 0.508 0.3048)
			(end -0.508 0.3048)
			(stroke
				(width 0.1)
				(type default)
			)
			(layer "B.Fab")
		)
		(pad "1" smd rect
			(at 0.5334 0 180)
			(size 0.7112 0.6096)
			(layers "B.Cu" "B.Mask" "B.Paste")
			(net "XP1R8V_FPGA_VCCAUX")
		)
		(pad "2" smd rect
			(at -0.5334 0 180)
			(size 0.7112 0.6096)
			(layers "B.Cu" "B.Mask" "B.Paste")
			(net "SG")
		)
		(zone
			(layer "B.Cu")
			(hatch none 0.5)
			(connect_pads
				(clearance 0)
			)
			(min_thickness 0.25)
			(keepout
				(tracks not_allowed)
				(vias allowed)
				(pads allowed)
				(copperpour not_allowed)
				(footprints allowed)
			)
			(placement
				(enabled no)
				(sheetname "")
			)
			(fill
				(thermal_gap 0.5)
				(thermal_bridge_width 0.5)
				(island_removal_mode 0)
			)
			(polygon
				(pts
					(xy 104.6988 -44.1452) (xy 104.6988 -44.7548) (xy 104.5464 -44.7548) (xy 104.5464 -44.1452)
				)
			)
		)
		(zone
			(layer "B.Cu")
			(hatch none 0.5)
			(connect_pads
				(clearance 0)
			)
			(min_thickness 0.25)
			(keepout
				(tracks allowed)
				(vias not_allowed)
				(pads allowed)
				(copperpour not_allowed)
				(footprints allowed)
			)
			(placement
				(enabled no)
				(sheetname "")
			)
			(fill
				(thermal_gap 0.5)
				(thermal_bridge_width 0.5)
				(island_removal_mode 0)
			)
			(polygon
				(pts
					(xy 104.6988 -44.1452) (xy 104.6988 -44.7548) (xy 104.5464 -44.7548) (xy 104.5464 -44.1452)
				)
			)
		)
	)
)
